# S9S_MB_2U (Grand Teton) — schematic netlist excerpt (pin names and nets, part order shuffled) for the footprints in the layout excerpt that follows; sources: Cadence DE-HDL packaged netlist, KiCad conversion of 03242023_DA0F0TMBIJ0_F0T_Motherboard_J_brd_V01_OCP.brd

C1536  Q_CAP_DIFFBUS  DIFF BUS_0.22UF 6.3V 20% X6S  pkg C0201  page 177 : \1\ = P5E_CPU1_PE3_TX_C_DN<5> ; \2\ = P5E_CPU1_PE3_TX_DN<5>
PL3  Q_INDUCTOR  300NH/33A IND  pkg SMLF  page 276 : \1\ = SW_PVCCFA_EHV_CPU0_SW1 ; \2\ = PVCCFA_EHV_CPU0
C954  Q_CAP_DIFFBUS  DIFF BUS_0.22UF 6.3V 20% X6S  pkg C0201  page 173 : \1\ = P5E_CPU0_PE2_TX_C_DN<5> ; \2\ = P5E_CPU0_PE2_TX_DN<5>
R2125  Q_RES  4.7K 5% CHIP  pkg 0402LF  page 191 : A = P3V3_AUX ; B = SMB_PCIE_E1S_ISO_EN

(kicad_pcb
	(version 20260206)
	(generator "pcbnew")
	(generator_version "10.0")
	(general
		(thickness 1.6)
		(legacy_teardrops no)
	)
	(paper "A4")
	(title_block
		(title "03242023_DA0F0TMBIJ0_F0T_Motherboard_J_brd_V01_OCP.brd")
		(comment 1 "Grand Teton / footprints 3113-3116 of 6105")
	)
	(layers
		(0 "F.Cu" signal "TOP")
		(4 "In1.Cu" signal "GND")
		(6 "In2.Cu" signal "IN1")
		(8 "In3.Cu" signal "GND1")
		(10 "In4.Cu" signal "IN2")
		(12 "In5.Cu" signal "GND2")
		(14 "In6.Cu" signal "IN3")
		(16 "In7.Cu" signal "GND3")
		(18 "In8.Cu" signal "VCC")
		(20 "In9.Cu" signal "VCC1")
		(22 "In10.Cu" signal "GND4")
		(24 "In11.Cu" signal "IN4")
		(26 "In12.Cu" signal "GND5")
		(28 "In13.Cu" signal "IN5")
		(30 "In14.Cu" signal "GND6")
		(32 "In15.Cu" signal "IN6")
		(34 "In16.Cu" signal "GND7")
		(2 "B.Cu" signal "BOTTOM")
		(9 "F.Adhes" user "F.Adhesive")
		(11 "B.Adhes" user "B.Adhesive")
		(13 "F.Paste" user "Package Geometry/Pastemask Top")
		(15 "B.Paste" user "Package Geometry/Pastemask Bottom")
		(5 "F.SilkS" user "Ref Des/Silkscreen Top")
		(7 "B.SilkS" user "Ref Des/Silkscreen Bottom")
		(1 "F.Mask" user "Board Geometry/Soldermask Top")
		(3 "B.Mask" user "Board Geometry/Soldermask Bottom")
		(17 "Dwgs.User" user "User.Drawings")
		(19 "Cmts.User" user "User.Comments")
		(21 "Eco1.User" user "User.Eco1")
		(23 "Eco2.User" user "User.Eco2")
		(25 "Edge.Cuts" user "Board Geometry/Outline")
		(27 "Margin" user)
		(31 "F.CrtYd" user "Package Geometry/Place Bound Top")
		(29 "B.CrtYd" user "Package Geometry/Place Bound Bottom")
		(35 "F.Fab" user "Ref Des/Assembly Top")
		(33 "B.Fab" user "Ref Des/Assembly Bottom")
	)
	(footprint ""
		(layer "F.Cu")
		(at 402.94433 -402.371052 -90)
		(property "Reference" "C954"
			(at 0 0 270)
			(layer "F.SilkS")
			(hide yes)
			(effects
				(font
					(size 1.27 1.27)
				)
			)
		)
		(property "Value" ""
			(at 0 0 270)
			(layer "F.Fab")
			(effects
				(font
					(size 1.27 1.27)
				)
			)
		)
		(duplicate_pad_numbers_are_jumpers no)
		(fp_line
			(start -0.299974 0.150114)
			(end -0.299974 -0.150114)
			(stroke
				(width 0.1)
				(type default)
			)
			(layer "F.Fab")
		)
		(fp_line
			(start 0.299974 0.150114)
			(end -0.299974 0.150114)
			(stroke
				(width 0.1)
				(type default)
			)
			(layer "F.Fab")
		)
		(fp_line
			(start -0.299974 -0.150114)
			(end 0.299974 -0.150114)
			(stroke
				(width 0.1)
				(type default)
			)
			(layer "F.Fab")
		)
		(fp_line
			(start 0.299974 -0.150114)
			(end 0.299974 0.150114)
			(stroke
				(width 0.1)
				(type default)
			)
			(layer "F.Fab")
		)
		(pad "1" smd rect
			(at -0.2667 0 270)
			(size 0.3048 0.381)
			(layers "F.Cu" "F.Mask" "F.Paste")
			(net "P5E_CPU0_PE2_TX_C_DN<5>")
		)
		(pad "2" smd rect
			(at 0.2667 0 270)
			(size 0.3048 0.381)
			(layers "F.Cu" "F.Mask" "F.Paste")
			(net "P5E_CPU0_PE2_TX_DN<5>")
		)
	)
	(footprint ""
		(layer "F.Cu")
		(at 152.108154 -408.517344 -90)
		(property "Reference" "C1536"
			(at 0 0 270)
			(layer "F.SilkS")
			(hide yes)
			(effects
				(font
					(size 1.27 1.27)
				)
			)
		)
		(property "Value" ""
			(at 0 0 270)
			(layer "F.Fab")
			(effects
				(font
					(size 1.27 1.27)
				)
			)
		)
		(duplicate_pad_numbers_are_jumpers no)
		(fp_line
			(start -0.299974 0.150114)
			(end -0.299974 -0.150114)
			(stroke
				(width 0.1)
				(type default)
			)
			(layer "F.Fab")
		)
		(fp_line
			(start 0.299974 0.150114)
			(end -0.299974 0.150114)
			(stroke
				(width 0.1)
				(type default)
			)
			(layer "F.Fab")
		)
		(fp_line
			(start -0.299974 -0.150114)
			(end 0.299974 -0.150114)
			(stroke
				(width 0.1)
				(type default)
			)
			(layer "F.Fab")
		)
		(fp_line
			(start 0.299974 -0.150114)
			(end 0.299974 0.150114)
			(stroke
				(width 0.1)
				(type default)
			)
			(layer "F.Fab")
		)
		(pad "1" smd rect
			(at -0.2667 0 270)
			(size 0.3048 0.381)
			(layers "F.Cu" "F.Mask" "F.Paste")
			(net "P5E_CPU1_PE3_TX_C_DN<5>")
		)
		(pad "2" smd rect
			(at 0.2667 0 270)
			(size 0.3048 0.381)
			(layers "F.Cu" "F.Mask" "F.Paste")
			(net "P5E_CPU1_PE3_TX_DN<5>")
		)
	)
	(footprint ""
		(layer "F.Cu")
		(at 162.848036 -63.297308 180)
		(property "Reference" "R2125"
			(at 0 0 180)
			(layer "F.SilkS")
			(hide yes)
			(effects
				(font
					(size 1.27 1.27)
				)
			)
		)
		(property "Value" ""
			(at 0 0 180)
			(layer "F.Fab")
			(effects
				(font
					(size 1.27 1.27)
				)
			)
		)
		(duplicate_pad_numbers_are_jumpers no)
		(fp_line
			(start 0.7874 0.4064)
			(end -0.7874 0.4064)
			(stroke
				(width 0.1524)
				(type default)
			)
			(layer "F.SilkS")
		)
		(fp_line
			(start 0.7874 -0.4064)
			(end 0.7874 0.4064)
			(stroke
				(width 0.1524)
				(type default)
			)
			(layer "F.SilkS")
		)
		(fp_line
			(start -0.7874 0.4064)
			(end -0.7874 -0.4064)
			(stroke
				(width 0.1524)
				(type default)
			)
			(layer "F.SilkS")
		)
		(fp_line
			(start -0.7874 -0.4064)
			(end 0.7874 -0.4064)
			(stroke
				(width 0.1524)
				(type default)
			)
			(layer "F.SilkS")
		)
		(fp_line
			(start 0.67945 0.3048)
			(end 0.120396 0.3048)
			(stroke
				(width 0.1)
				(type default)
			)
			(layer "F.Fab")
		)
		(fp_line
			(start 0.67945 -0.3048)
			(end 0.67945 0.3048)
			(stroke
				(width 0.1)
				(type default)
			)
			(layer "F.Fab")
		)
		(fp_line
			(start 0.12065 -0.2794)
			(end 0.12065 -0.3048)
			(stroke
				(width 0.1)
				(type default)
			)
			(layer "F.Fab")
		)
		(fp_line
			(start 0.12065 -0.3048)
			(end 0.67945 -0.3048)
			(stroke
				(width 0.1)
				(type default)
			)
			(layer "F.Fab")
		)
		(fp_line
			(start 0.120396 0.3048)
			(end 0.120396 0.2794)
			(stroke
				(width 0.1)
				(type default)
			)
			(layer "F.Fab")
		)
		(fp_line
			(start 0.120396 0.2794)
			(end -0.12065 0.2794)
			(stroke
				(width 0.1)
				(type default)
			)
			(layer "F.Fab")
		)
		(fp_line
			(start -0.12065 0.3048)
			(end -0.67945 0.3048)
			(stroke
				(width 0.1)
				(type default)
			)
			(layer "F.Fab")
		)
		(fp_line
			(start -0.12065 0.2794)
			(end -0.12065 0.3048)
			(stroke
				(width 0.1)
				(type default)
			)
			(layer "F.Fab")
		)
		(fp_line
			(start -0.12065 -0.2794)
			(end 0.12065 -0.2794)
			(stroke
				(width 0.1)
				(type default)
			)
			(layer "F.Fab")
		)
		(fp_line
			(start -0.12065 -0.305054)
			(end -0.12065 -0.2794)
			(stroke
				(width 0.1)
				(type default)
			)
			(layer "F.Fab")
		)
		(fp_line
			(start -0.67945 0.3048)
			(end -0.67945 -0.305054)
			(stroke
				(width 0.1)
				(type default)
			)
			(layer "F.Fab")
		)
		(fp_line
			(start -0.67945 -0.305054)
			(end -0.12065 -0.305054)
			(stroke
				(width 0.1)
				(type default)
			)
			(layer "F.Fab")
		)
		(pad "1" smd circle
			(at -0.40005 0 180)
			(size 0 0)
			(layers "F.Cu" "F.Mask" "F.Paste")
			(net "P3V3_AUX")
		)
		(pad "2" smd circle
			(at 0.40005 0 180)
			(size 0 0)
			(layers "F.Cu" "F.Mask" "F.Paste")
			(net "SMB_PCIE_E1S_ISO_EN")
		)
	)
	(footprint ""
		(layer "F.Cu")
		(at 410.094176 -153.069036 180)
		(property "Reference" "PL3"
			(at -1.462786 -4.512564 0)
			(unlocked yes)
			(layer "F.SilkS")
			(effects
				(font
					(size 0.7874 0.5842)
					(thickness 0.1524)
				)
				(justify left)
			)
		)
		(property "Value" ""
			(at 0 0 180)
			(layer "F.Fab")
			(effects
				(font
					(size 1.27 1.27)
				)
			)
		)
		(duplicate_pad_numbers_are_jumpers no)
		(fp_line
			(start 4.800092 3.199892)
			(end -4.800092 3.199892)
			(stroke
				(width 0.1524)
				(type default)
			)
			(layer "F.SilkS")
		)
		(fp_line
			(start 4.800092 1.6891)
			(end 4.800092 3.199892)
			(stroke
				(width 0.1524)
				(type default)
			)
			(layer "F.SilkS")
		)
		(fp_line
			(start 4.800092 -3.199892)
			(end 4.800092 -1.6891)
			(stroke
				(width 0.1524)
				(type default)
			)
			(layer "F.SilkS")
		)
		(fp_line
			(start -4.800092 3.199892)
			(end -4.800092 1.6891)
			(stroke
				(width 0.1524)
				(type default)
			)
			(layer "F.SilkS")
		)
		(fp_line
			(start -4.800092 -1.6891)
			(end -4.800092 -3.199892)
			(stroke
				(width 0.1524)
				(type default)
			)
			(layer "F.SilkS")
		)
		(fp_line
			(start -4.800092 -3.199892)
			(end 4.800092 -3.199892)
			(stroke
				(width 0.1524)
				(type default)
			)
			(layer "F.SilkS")
		)
		(fp_line
			(start 4.800092 3.199892)
			(end -4.800092 3.199892)
			(stroke
				(width 0.1)
				(type default)
			)
			(layer "F.Fab")
		)
		(fp_line
			(start 4.800092 -3.199892)
			(end 4.800092 3.199892)
			(stroke
				(width 0.1)
				(type default)
			)
			(layer "F.Fab")
		)
		(fp_line
			(start -4.800092 3.199892)
			(end -4.800092 -3.199892)
			(stroke
				(width 0.1)
				(type default)
			)
			(layer "F.Fab")
		)
		(fp_line
			(start -4.800092 -3.199892)
			(end 4.800092 -3.199892)
			(stroke
				(width 0.1)
				(type default)
			)
			(layer "F.Fab")
		)
		(pad "1" smd rect
			(at -3.350006 0 270)
			(size 3.0988 3.2004)
			(layers "F.Cu" "F.Mask" "F.Paste")
			(net "SW_PVCCFA_EHV_CPU0_SW1")
		)
		(pad "2" smd rect
			(at 3.350006 0 270)
			(size 3.0988 3.2004)
			(layers "F.Cu" "F.Mask" "F.Paste")
			(net "PVCCFA_EHV_CPU0")
		)
	)
)
